FILE_TYPE = MACRO_DRAWING;
SET COLOR_WIRE YELLOW;
SET COLOR_PROP MONO;
SET COLOR_DOT WHITE;
SET COLOR_ARC YELLOW;
SET COLOR_BODY GREEN;
SET COLOR_NOTE MONO;
SET PROP_DISPLAY VALUE;
SET PAGE_NUMBER P135;
FORCEADD P3V3_STBY..1
(200 2525);
FORCEPROP 3 LASTPIN (200 2475) SIG_NAME P3V3_STBY\g
J 0
(210 2485);
DISPLAY 0.659574 (210 2485);
PAINT MONO (210 2485);
DISPLAY INVISIBLE (210 2485);
FORCEPROP 1 LAST VOLTAGE 3.3V
J 0
(155 2482);
DISPLAY 0.340426 (155 2482);
PAINT SKYBLUE (155 2482);
DISPLAY INVISIBLE (155 2482);
FORCEPROP 1 LAST SIZE 1B
J 0
(245 2547);
DISPLAY 0.340426 (245 2547);
PAINT GREEN (245 2547);
DISPLAY INVISIBLE (245 2547);
FORCEPROP 2 LAST CDS_LIB mstr_symbols
J 0
(200 2525);
PAINT MONO (200 2525);
DISPLAY INVISIBLE (200 2525);
FORCEPROP 1 LAST PATH I106
J 0
(245 2527);
DISPLAY 0.340426 (245 2527);
PAINT GREEN (245 2527);
DISPLAY INVISIBLE (245 2527);
FORCEPROP 1 LAST BODY_TYPE PLUMBING
J 0
(155 2482);
DISPLAY 0.340426 (155 2482);
PAINT GREEN (155 2482);
DISPLAY INVISIBLE (155 2482);
FORCEPROP 1 LAST HDL_POWER P3V3_STBY
J 0
(-100 2400);
DISPLAY 0.872340 (-100 2400);
PAINT ORANGE (-100 2400);
DISPLAY INVISIBLE (-100 2400);
FORCEADD RES..2
(200 2225);
FORCEPROP 1 LAST PART_NUMBER G21796-016
J 0
(240 2100);
DISPLAY 0.617021 (240 2100);
PAINT BLUE (240 2100);
FORCEPROP 1 LAST PACK_TYPE 0402
J 0
(240 2050);
DISPLAY 0.617021 (240 2050);
PAINT SKYBLUE (240 2050);
FORCEPROP 1 LAST TOLERANCE 1%
J 0
(245 2250);
DISPLAY 0.617021 (245 2250);
PAINT SKYBLUE (245 2250);
FORCEPROP 1 LAST MATERIAL CHIP
J 0
(240 2150);
DISPLAY 0.617021 (240 2150);
PAINT SKYBLUE (240 2150);
FORCEPROP 1 LAST WATTAGE 1/16W
J 0
(240 2200);
DISPLAY 0.617021 (240 2200);
PAINT SKYBLUE (240 2200);
FORCEPROP 1 LASTPIN (200 2325) $PN 1
J 0
(205 2287);
DISPLAY 0.617021 (205 2287);
PAINT ORANGE (205 2287);
FORCEPROP 1 LASTPIN (200 2125) $PN 2
J 0
(205 2135);
DISPLAY 0.617021 (205 2135);
PAINT ORANGE (205 2135);
FORCEPROP 1 LAST VALUE 10.0K
J 0
(245 2300);
DISPLAY 0.617021 (245 2300);
PAINT SKYBLUE (245 2300);
FORCEPROP 1 LAST LOCATION R2P19
J 0
(245 2350);
DISPLAY 0.617021 (245 2350);
PAINT AQUA (245 2350);
FORCEPROP 0 LAST ROOM CPLD
J 0
(250 2450);
DISPLAY 1.021277 (250 2450);
PAINT ORANGE (250 2450);
DISPLAY INVISIBLE (250 2450);
FORCEPROP 2 LAST SEC_TYPE 0402
J 0
(250 2450);
DISPLAY 1.021277 (250 2450);
PAINT ORANGE (250 2450);
DISPLAY INVISIBLE (250 2450);
FORCEPROP 0 LAST BOM_COST CPLD
J 0
(250 2450);
DISPLAY 1.021277 (250 2450);
PAINT ORANGE (250 2450);
DISPLAY INVISIBLE (250 2450);
FORCEPROP 2 LAST SEC 1
J 0
(250 2450);
PAINT MONO (250 2450);
DISPLAY INVISIBLE (250 2450);
FORCEPROP 1 LAST PATH I107
J 0
(250 2400);
DISPLAY 0.978723 (250 2400);
PAINT WHITE (250 2400);
DISPLAY INVISIBLE (250 2400);
FORCEPROP 2 LAST CDS_LIB mstr_discrete
J 0
(200 2225);
PAINT MONO (200 2225);
DISPLAY INVISIBLE (200 2225);
FORCEADD OFFPAGE..2
(675 1950);
FORCEPROP 2 LAST $XR1 190 
J 0
(984 1950);
DISPLAY 0.638298 (984 1950);
PAINT MONO (984 1950);
FORCEPROP 2 LAST $XR0 120 
J 0
(864 1950);
DISPLAY 0.638298 (864 1950);
PAINT MONO (864 1950);
FORCEPROP 2 LAST CDS_LIB mstr_standard
J 0
(675 1950);
PAINT MONO (675 1950);
DISPLAY INVISIBLE (675 1950);
FORCEPROP 2 LAST BOM_COST SB
J 0
(875 2000);
PAINT ORANGE (875 2000);
DISPLAY INVISIBLE (875 2000);
FORCEPROP 2 LAST PATH I108
J 0
(1000 2000);
DISPLAY 1.021277 (1000 2000);
PAINT ORANGE (1000 2000);
DISPLAY INVISIBLE (1000 2000);
FORCEPROP 2 LAST ROOM WBG_HEADERS_BIOS
J 0
(450 2025);
PAINT ORANGE (450 2025);
DISPLAY INVISIBLE (450 2025);
FORCEPROP 1 LAST OFFPAGE TRUE
J 0
(1000 1825);
PAINT GREEN (1000 1825);
DISPLAY INVISIBLE (1000 1825);
FORCEPROP 1 LAST COMMENT_BODY TRUE
J 0
(630 1855);
DISPLAY 0.978723 (630 1855);
PAINT GREEN (630 1855);
DISPLAY INVISIBLE (630 1855);
FORCEADD OFFPAGE..2
(675 1800);
FORCEPROP 2 LAST $XR0 190 
J 0
(864 1800);
DISPLAY 0.638298 (864 1800);
PAINT MONO (864 1800);
FORCEPROP 2 LAST CDS_LIB mstr_standard
J 0
(675 1800);
PAINT ORANGE (675 1800);
DISPLAY INVISIBLE (675 1800);
FORCEPROP 2 LAST PATH I109
J 0
(875 1850);
DISPLAY 1.021277 (875 1850);
PAINT ORANGE (875 1850);
DISPLAY INVISIBLE (875 1850);
FORCEPROP 1 LAST OFFPAGE TRUE
J 0
(1000 1675);
DISPLAY 0.872340 (1000 1675);
PAINT GREEN (1000 1675);
DISPLAY INVISIBLE (1000 1675);
FORCEPROP 1 LAST COMMENT_BODY TRUE
J 0
(630 1705);
DISPLAY 0.872340 (630 1705);
PAINT GREEN (630 1705);
DISPLAY INVISIBLE (630 1705);
FORCEADD OFFPAGE..2
(-1500 4525);
FORCEPROP 2 LASTPIN (-1550 4525) SIG_NAME FM_QAT_EN_N
J 2
(-1560 4535);
DISPLAY 0.617021 (-1560 4535);
PAINT ORANGE (-1560 4535);
FORCEPROP 2 LAST $XR0 119 
J 0
(-1311 4525);
DISPLAY 0.638298 (-1311 4525);
PAINT MONO (-1311 4525);
FORCEPROP 2 LAST CDS_LIB mstr_standard
J 0
(-1500 4525);
PAINT ORANGE (-1500 4525);
DISPLAY INVISIBLE (-1500 4525);
FORCEPROP 2 LAST PATH I110
J 0
(-1300 4575);
DISPLAY 1.021277 (-1300 4575);
PAINT ORANGE (-1300 4575);
DISPLAY INVISIBLE (-1300 4575);
FORCEPROP 1 LAST OFFPAGE TRUE
J 0
(-1175 4400);
DISPLAY 0.872340 (-1175 4400);
PAINT GREEN (-1175 4400);
DISPLAY INVISIBLE (-1175 4400);
FORCEPROP 1 LAST COMMENT_BODY TRUE
J 0
(-1545 4430);
DISPLAY 0.872340 (-1545 4430);
PAINT GREEN (-1545 4430);
DISPLAY INVISIBLE (-1545 4430);
FORCEADD P3V3_STBY..1
(-2150 5025);
FORCEPROP 3 LASTPIN (-2150 4975) SIG_NAME P3V3_STBY\g
J 0
(-2140 4985);
DISPLAY 0.659574 (-2140 4985);
PAINT MONO (-2140 4985);
DISPLAY INVISIBLE (-2140 4985);
FORCEPROP 1 LAST VOLTAGE 3.3V
J 0
(-2195 4982);
DISPLAY 0.340426 (-2195 4982);
PAINT SKYBLUE (-2195 4982);
DISPLAY INVISIBLE (-2195 4982);
FORCEPROP 2 LAST CDS_LIB mstr_symbols
J 0
(-2150 5025);
PAINT ORANGE (-2150 5025);
DISPLAY INVISIBLE (-2150 5025);
FORCEPROP 1 LAST SIZE 1B
J 0
(-2105 5047);
DISPLAY 0.340426 (-2105 5047);
PAINT GREEN (-2105 5047);
DISPLAY INVISIBLE (-2105 5047);
FORCEPROP 1 LAST PATH I111
J 0
(-2105 5027);
DISPLAY 0.340426 (-2105 5027);
PAINT GREEN (-2105 5027);
DISPLAY INVISIBLE (-2105 5027);
FORCEPROP 1 LAST BODY_TYPE PLUMBING
J 0
(-2195 4982);
DISPLAY 0.340426 (-2195 4982);
PAINT GREEN (-2195 4982);
DISPLAY INVISIBLE (-2195 4982);
FORCEPROP 1 LAST HDL_POWER P3V3_STBY
J 0
(-2450 4900);
DISPLAY 0.872340 (-2450 4900);
PAINT ORANGE (-2450 4900);
DISPLAY INVISIBLE (-2450 4900);
FORCEADD RES..2
(-2150 4775);
FORCEPROP 1 LAST LOCATION R2N23
J 0
(-2105 4900);
DISPLAY 0.617021 (-2105 4900);
PAINT AQUA (-2105 4900);
FORCEPROP 1 LAST PART_NUMBER G21796-016
J 0
(-2110 4650);
DISPLAY 0.617021 (-2110 4650);
PAINT BLUE (-2110 4650);
FORCEPROP 1 LAST VALUE 10.0K
J 0
(-2105 4850);
DISPLAY 0.617021 (-2105 4850);
PAINT SKYBLUE (-2105 4850);
FORCEPROP 1 LAST TOLERANCE 1%
J 0
(-2105 4800);
DISPLAY 0.617021 (-2105 4800);
PAINT SKYBLUE (-2105 4800);
FORCEPROP 1 LAST PACK_TYPE 0402
J 0
(-2110 4600);
DISPLAY 0.617021 (-2110 4600);
PAINT SKYBLUE (-2110 4600);
FORCEPROP 1 LAST MATERIAL CHIP
J 0
(-2110 4700);
DISPLAY 0.617021 (-2110 4700);
PAINT SKYBLUE (-2110 4700);
FORCEPROP 1 LAST WATTAGE 1/16W
J 0
(-2110 4750);
DISPLAY 0.617021 (-2110 4750);
PAINT SKYBLUE (-2110 4750);
FORCEPROP 1 LASTPIN (-2150 4675) $PN 2
J 0
(-2145 4685);
DISPLAY 0.617021 (-2145 4685);
PAINT ORANGE (-2145 4685);
FORCEPROP 1 LASTPIN (-2150 4875) $PN 1
J 0
(-2145 4837);
DISPLAY 0.617021 (-2145 4837);
PAINT ORANGE (-2145 4837);
FORCEPROP 2 LAST ROOM SB
J 0
(-2100 4950);
PAINT MONO (-2100 4950);
DISPLAY INVISIBLE (-2100 4950);
FORCEPROP 2 LAST CDS_SEC 1
J 0
(-2100 5000);
PAINT MONO (-2100 5000);
DISPLAY INVISIBLE (-2100 5000);
FORCEPROP 2 LAST $SEC 1
J 0
(-2100 5000);
DISPLAY 0.680851 (-2100 5000);
PAINT MONO (-2100 5000);
DISPLAY INVISIBLE (-2100 5000);
FORCEPROP 2 LAST CDS_LOCATION R2N23
J 0
(-2105 4900);
DISPLAY 0.617021 (-2105 4900);
PAINT AQUA (-2105 4900);
DISPLAY INVISIBLE (-2105 4900);
FORCEPROP 1 LAST PATH I112
J 0
(-2100 4950);
DISPLAY 0.978723 (-2100 4950);
PAINT WHITE (-2100 4950);
DISPLAY INVISIBLE (-2100 4950);
FORCEPROP 2 LAST CDS_LIB mstr_discrete
J 0
(-2150 4775);
PAINT ORANGE (-2150 4775);
DISPLAY INVISIBLE (-2150 4775);
FORCEADD RES..2
(-2150 4325);
FORCEPROP 1 LAST PART_NUMBER G21796-026
J 0
(-2110 4200);
DISPLAY 0.617021 (-2110 4200);
PAINT BLUE (-2110 4200);
FORCEPROP 1 LAST MATERIAL EMPTY
J 0
(-2110 4250);
DISPLAY 0.617021 (-2110 4250);
PAINT RED (-2110 4250);
FORCEPROP 1 LAST LOCATION R2N24
J 0
(-2105 4450);
DISPLAY 0.617021 (-2105 4450);
PAINT AQUA (-2105 4450);
FORCEPROP 1 LAST TOLERANCE 1%
J 0
(-2105 4350);
DISPLAY 0.617021 (-2105 4350);
PAINT SKYBLUE (-2105 4350);
FORCEPROP 1 LAST PACK_TYPE 0402
J 0
(-2110 4150);
DISPLAY 0.617021 (-2110 4150);
PAINT SKYBLUE (-2110 4150);
FORCEPROP 1 LAST WATTAGE 1/16W
J 0
(-2110 4300);
DISPLAY 0.617021 (-2110 4300);
PAINT SKYBLUE (-2110 4300);
FORCEPROP 1 LASTPIN (-2150 4425) $PN 1
J 0
(-2145 4387);
DISPLAY 0.617021 (-2145 4387);
PAINT ORANGE (-2145 4387);
FORCEPROP 1 LASTPIN (-2150 4225) $PN 2
J 0
(-2145 4235);
DISPLAY 0.617021 (-2145 4235);
PAINT ORANGE (-2145 4235);
FORCEPROP 1 LAST VALUE 1.00K
J 0
(-2105 4400);
DISPLAY 0.617021 (-2105 4400);
PAINT SKYBLUE (-2105 4400);
FORCEPROP 2 LAST ROOM SB
J 0
(-2100 4500);
PAINT MONO (-2100 4500);
DISPLAY INVISIBLE (-2100 4500);
FORCEPROP 2 LAST SEC_TYPE 0402
J 0
(-2100 4550);
DISPLAY 1.021277 (-2100 4550);
PAINT ORANGE (-2100 4550);
DISPLAY INVISIBLE (-2100 4550);
FORCEPROP 2 LAST SEC 1
J 0
(-2100 4550);
DISPLAY 0.680851 (-2100 4550);
PAINT MONO (-2100 4550);
DISPLAY INVISIBLE (-2100 4550);
FORCEPROP 1 LAST PATH I113
J 0
(-2100 4500);
DISPLAY 0.978723 (-2100 4500);
PAINT WHITE (-2100 4500);
DISPLAY INVISIBLE (-2100 4500);
FORCEPROP 2 LAST CDS_LOCATION R2N24
J 0
(-2105 4450);
DISPLAY 0.617021 (-2105 4450);
PAINT AQUA (-2105 4450);
DISPLAY INVISIBLE (-2105 4450);
FORCEPROP 2 LAST CDS_LIB mstr_discrete
J 0
(-2150 4325);
PAINT ORANGE (-2150 4325);
DISPLAY INVISIBLE (-2150 4325);
FORCEADD GND..1
(-2150 4125);
FORCEPROP 3 LASTPIN (-2150 4175) SIG_NAME GND\g
J 0
(-2140 4185);
DISPLAY 0.659574 (-2140 4185);
PAINT MONO (-2140 4185);
DISPLAY INVISIBLE (-2140 4185);
FORCEPROP 1 LAST VOLTAGE 0.0V
J 0
(-2195 4082);
DISPLAY 0.340426 (-2195 4082);
PAINT SKYBLUE (-2195 4082);
DISPLAY INVISIBLE (-2195 4082);
FORCEPROP 2 LAST CDS_LIB mstr_symbols
J 0
(-2150 4125);
PAINT ORANGE (-2150 4125);
DISPLAY INVISIBLE (-2150 4125);
FORCEPROP 1 LAST PATH I114
J 0
(-2075 4125);
DISPLAY 0.872340 (-2075 4125);
PAINT AQUA (-2075 4125);
DISPLAY INVISIBLE (-2075 4125);
FORCEPROP 1 LAST SIZE 1B
J 0
(-2075 4075);
DISPLAY 0.872340 (-2075 4075);
PAINT AQUA (-2075 4075);
DISPLAY INVISIBLE (-2075 4075);
FORCEPROP 1 LAST BODY_TYPE PLUMBING
J 0
(-2195 4082);
DISPLAY 0.340426 (-2195 4082);
PAINT GREEN (-2195 4082);
DISPLAY INVISIBLE (-2195 4082);
FORCEPROP 1 LAST HDL_POWER GND
J 0
(-2150 4275);
DISPLAY 0.872340 (-2150 4275);
PAINT GREEN (-2150 4275);
DISPLAY INVISIBLE (-2150 4275);
FORCEADD OFFPAGE..3
(-2875 4500);
FORCEPROP 2 LAST $XR0 119 
J 0
(-2661 4500);
DISPLAY 0.638298 (-2661 4500);
PAINT MONO (-2661 4500);
FORCEPROP 2 LAST PATH I115
J 0
(-2650 4550);
DISPLAY 1.021277 (-2650 4550);
PAINT ORANGE (-2650 4550);
DISPLAY INVISIBLE (-2650 4550);
FORCEPROP 2 LAST ROOM WBG_HEADERS_BIOS
J 0
(-2675 4550);
PAINT MONO (-2675 4550);
DISPLAY INVISIBLE (-2675 4550);
FORCEPROP 2 LAST BOM_COST SB
J 0
(-2675 4550);
PAINT MONO (-2675 4550);
DISPLAY INVISIBLE (-2675 4550);
FORCEPROP 2 LAST CDS_LIB mstr_standard
J 0
(-2875 4500);
PAINT MONO (-2875 4500);
DISPLAY INVISIBLE (-2875 4500);
FORCEPROP 1 LAST OFFPAGE TRUE
J 0
(-2550 4375);
DISPLAY 0.872340 (-2550 4375);
PAINT GREEN (-2550 4375);
DISPLAY INVISIBLE (-2550 4375);
FORCEPROP 1 LAST COMMENT_BODY TRUE
J 0
(-2925 4400);
DISPLAY 0.872340 (-2925 4400);
PAINT GREEN (-2925 4400);
DISPLAY INVISIBLE (-2925 4400);
FORCEADD P3V3_STBY..1
(-3875 5150);
FORCEPROP 3 LASTPIN (-3875 5100) SIG_NAME P3V3_STBY\g
J 0
(-3865 5110);
DISPLAY 0.659574 (-3865 5110);
PAINT MONO (-3865 5110);
DISPLAY INVISIBLE (-3865 5110);
FORCEPROP 1 LAST VOLTAGE 3.3V
J 0
(-3920 5107);
DISPLAY 0.340426 (-3920 5107);
PAINT SKYBLUE (-3920 5107);
DISPLAY INVISIBLE (-3920 5107);
FORCEPROP 1 LAST SIZE 1B
J 0
(-3830 5172);
DISPLAY 0.340426 (-3830 5172);
PAINT GREEN (-3830 5172);
DISPLAY INVISIBLE (-3830 5172);
FORCEPROP 2 LAST CDS_LIB mstr_symbols
J 0
(-3875 5150);
PAINT ORANGE (-3875 5150);
DISPLAY INVISIBLE (-3875 5150);
FORCEPROP 1 LAST PATH I116
J 0
(-3830 5152);
DISPLAY 0.340426 (-3830 5152);
PAINT GREEN (-3830 5152);
DISPLAY INVISIBLE (-3830 5152);
FORCEPROP 1 LAST BODY_TYPE PLUMBING
J 0
(-3920 5107);
DISPLAY 0.340426 (-3920 5107);
PAINT GREEN (-3920 5107);
DISPLAY INVISIBLE (-3920 5107);
FORCEPROP 1 LAST HDL_POWER P3V3_STBY
J 0
(-4175 5025);
DISPLAY 0.872340 (-4175 5025);
PAINT ORANGE (-4175 5025);
DISPLAY INVISIBLE (-4175 5025);
FORCEADD RES..1
R 1
(-3875 4900);
FORCEPROP 1 LAST MATERIAL CHIP
J 0
(-3850 4775);
DISPLAY 0.617021 (-3850 4775);
PAINT SKYBLUE (-3850 4775);
FORCEPROP 1 LAST WATTAGE 1/16W
J 0
(-3850 4825);
DISPLAY 0.617021 (-3850 4825);
PAINT SKYBLUE (-3850 4825);
FORCEPROP 1 LASTPIN (-3875 4800) $PN 1
J 0
(-3912 4812);
DISPLAY 0.617021 (-3912 4812);
PAINT MONO (-3912 4812);
FORCEPROP 1 LAST LOCATION R9A12
J 0
(-3850 5000);
DISPLAY 0.617021 (-3850 5000);
PAINT AQUA (-3850 5000);
FORCEPROP 1 LAST VALUE 2.21K
J 0
(-3850 4925);
DISPLAY 0.617021 (-3850 4925);
PAINT SKYBLUE (-3850 4925);
FORCEPROP 1 LAST TOLERANCE 1%
J 0
(-3850 4875);
DISPLAY 0.617021 (-3850 4875);
PAINT SKYBLUE (-3850 4875);
FORCEPROP 1 LAST PACK_TYPE 0402
J 0
(-3850 4650);
DISPLAY 0.617021 (-3850 4650);
PAINT SKYBLUE (-3850 4650);
FORCEPROP 1 LASTPIN (-3875 5000) $PN 2
J 0
(-3912 4962);
DISPLAY 0.617021 (-3912 4962);
PAINT MONO (-3912 4962);
FORCEPROP 1 LAST PART_NUMBER G21796-112
J 0
(-3850 4725);
DISPLAY 0.617021 (-3850 4725);
PAINT BLUE (-3850 4725);
FORCEPROP 2 LAST ROOM SB
J 0
(-3850 5050);
PAINT MONO (-3850 5050);
DISPLAY INVISIBLE (-3850 5050);
FORCEPROP 2 LAST CDS_LOCATION R9A12
J 0
(-3850 5000);
DISPLAY 0.617021 (-3850 5000);
PAINT AQUA (-3850 5000);
DISPLAY INVISIBLE (-3850 5000);
FORCEPROP 2 LAST $SEC 1
J 0
(-3850 5050);
DISPLAY 0.936170 (-3850 5050);
PAINT MONO (-3850 5050);
DISPLAY INVISIBLE (-3850 5050);
FORCEPROP 2 LAST CDS_SEC 1
J 0
(-3850 5050);
DISPLAY 1.404255 (-3850 5050);
PAINT ORANGE (-3850 5050);
DISPLAY INVISIBLE (-3850 5050);
FORCEPROP 2 LAST BOM_COST SB
J 0
(-3850 5050);
PAINT MONO (-3850 5050);
DISPLAY INVISIBLE (-3850 5050);
FORCEPROP 2 LAST CDS_LIB mstr_discrete
R 1
J 0
(-3875 4900);
PAINT MONO (-3875 4900);
DISPLAY INVISIBLE (-3875 4900);
FORCEPROP 1 LAST PATH I117
R 1
J 0
(-4025 4850);
DISPLAY 0.978723 (-4025 4850);
PAINT WHITE (-4025 4850);
DISPLAY INVISIBLE (-4025 4850);
FORCEADD RES..1
(-3650 4500);
FORCEPROP 1 LAST VALUE 33.2
J 2
(-3675 4400);
DISPLAY 0.617021 (-3675 4400);
PAINT SKYBLUE (-3675 4400);
FORCEPROP 1 LAST WATTAGE 1/16W
J 2
(-3675 4350);
DISPLAY 0.617021 (-3675 4350);
PAINT SKYBLUE (-3675 4350);
FORCEPROP 1 LAST PART_NUMBER G21796-074
J 0
(-3900 4275);
DISPLAY 0.617021 (-3900 4275);
PAINT BLUE (-3900 4275);
FORCEPROP 1 LAST TOLERANCE 1%
J 0
(-3650 4400);
DISPLAY 0.617021 (-3650 4400);
PAINT SKYBLUE (-3650 4400);
FORCEPROP 1 LAST PACK_TYPE 0402
J 0
(-3400 4350);
DISPLAY 0.617021 (-3400 4350);
PAINT SKYBLUE (-3400 4350);
FORCEPROP 1 LAST MATERIAL CHIP
J 0
(-3650 4350);
DISPLAY 0.617021 (-3650 4350);
PAINT SKYBLUE (-3650 4350);
FORCEPROP 1 LASTPIN (-3550 4500) $PN 2
J 0
(-3588 4512);
DISPLAY 0.617021 (-3588 4512);
PAINT MONO (-3588 4512);
FORCEPROP 1 LASTPIN (-3750 4500) $PN 1
J 0
(-3738 4512);
DISPLAY 0.617021 (-3738 4512);
PAINT MONO (-3738 4512);
FORCEPROP 1 LAST LOCATION R9A13
J 0
(-3700 4550);
DISPLAY 0.617021 (-3700 4550);
PAINT AQUA (-3700 4550);
FORCEPROP 2 LAST ROOM SB
J 0
(-3700 4600);
PAINT MONO (-3700 4600);
DISPLAY INVISIBLE (-3700 4600);
FORCEPROP 1 LAST PATH I118
J 0
(-3700 4650);
DISPLAY 0.978723 (-3700 4650);
PAINT WHITE (-3700 4650);
DISPLAY INVISIBLE (-3700 4650);
FORCEPROP 2 LAST $SEC 1
J 0
(-3700 4700);
DISPLAY 0.936170 (-3700 4700);
PAINT MONO (-3700 4700);
DISPLAY INVISIBLE (-3700 4700);
FORCEPROP 2 LAST CDS_SEC 1
J 0
(-3700 4700);
DISPLAY 1.404255 (-3700 4700);
PAINT ORANGE (-3700 4700);
DISPLAY INVISIBLE (-3700 4700);
FORCEPROP 2 LAST BOM_COST SB
J 0
(-3700 4600);
PAINT MONO (-3700 4600);
DISPLAY INVISIBLE (-3700 4600);
FORCEPROP 2 LAST CDS_LOCATION R9A13
J 0
(-3700 4550);
DISPLAY 0.617021 (-3700 4550);
PAINT AQUA (-3700 4550);
DISPLAY INVISIBLE (-3700 4550);
FORCEPROP 2 LAST CDS_LIB mstr_discrete
J 0
(-3650 4500);
PAINT MONO (-3650 4500);
DISPLAY INVISIBLE (-3650 4500);
FORCEADD P3V3_STBY..1
(-225 2525);
FORCEPROP 3 LASTPIN (-225 2475) SIG_NAME P3V3_STBY\g
J 0
(-215 2485);
DISPLAY 0.659574 (-215 2485);
PAINT MONO (-215 2485);
DISPLAY INVISIBLE (-215 2485);
FORCEPROP 1 LAST VOLTAGE 3.3V
J 0
(-270 2482);
DISPLAY 0.340426 (-270 2482);
PAINT SKYBLUE (-270 2482);
DISPLAY INVISIBLE (-270 2482);
FORCEPROP 2 LAST CDS_LIB mstr_symbols
J 0
(-225 2525);
PAINT MONO (-225 2525);
DISPLAY INVISIBLE (-225 2525);
FORCEPROP 1 LAST SIZE 1B
J 0
(-180 2547);
DISPLAY 0.340426 (-180 2547);
PAINT GREEN (-180 2547);
DISPLAY INVISIBLE (-180 2547);
FORCEPROP 1 LAST PATH I119
J 0
(-180 2527);
DISPLAY 0.340426 (-180 2527);
PAINT GREEN (-180 2527);
DISPLAY INVISIBLE (-180 2527);
FORCEPROP 1 LAST BODY_TYPE PLUMBING
J 0
(-270 2482);
DISPLAY 0.340426 (-270 2482);
PAINT GREEN (-270 2482);
DISPLAY INVISIBLE (-270 2482);
FORCEPROP 1 LAST HDL_POWER P3V3_STBY
J 0
(-525 2400);
DISPLAY 0.872340 (-525 2400);
PAINT ORANGE (-525 2400);
DISPLAY INVISIBLE (-525 2400);
FORCEADD RES..2
(-225 2250);
FORCEPROP 1 LAST WATTAGE 1/16W
J 0
(-185 2225);
DISPLAY 0.617021 (-185 2225);
PAINT SKYBLUE (-185 2225);
FORCEPROP 1 LAST PACK_TYPE 0402
J 0
(-185 2075);
DISPLAY 0.617021 (-185 2075);
PAINT SKYBLUE (-185 2075);
FORCEPROP 1 LAST PART_NUMBER G21796-026
J 0
(-185 2125);
DISPLAY 0.617021 (-185 2125);
PAINT BLUE (-185 2125);
FORCEPROP 1 LAST VALUE 1.00K
J 0
(-180 2325);
DISPLAY 0.617021 (-180 2325);
PAINT SKYBLUE (-180 2325);
FORCEPROP 1 LAST TOLERANCE 1%
J 0
(-180 2275);
DISPLAY 0.617021 (-180 2275);
PAINT SKYBLUE (-180 2275);
FORCEPROP 1 LAST MATERIAL CHIP
J 0
(-185 2175);
DISPLAY 0.617021 (-185 2175);
PAINT SKYBLUE (-185 2175);
FORCEPROP 1 LASTPIN (-225 2350) $PN 1
J 0
(-220 2312);
DISPLAY 0.617021 (-220 2312);
PAINT ORANGE (-220 2312);
FORCEPROP 1 LASTPIN (-225 2150) $PN 2
J 0
(-220 2160);
DISPLAY 0.617021 (-220 2160);
PAINT ORANGE (-220 2160);
FORCEPROP 1 LAST LOCATION R8D21
J 0
(-180 2375);
DISPLAY 0.617021 (-180 2375);
PAINT AQUA (-180 2375);
FORCEPROP 2 LAST ROOM SB
J 0
(-275 2075);
DISPLAY 1.361702 (-275 2075);
PAINT ORANGE (-275 2075);
DISPLAY INVISIBLE (-275 2075);
FORCEPROP 2 LAST BOM_COST SB
R 3
J 0
(0 2200);
PAINT ORANGE (0 2200);
DISPLAY INVISIBLE (0 2200);
FORCEPROP 1 LAST PATH I120
J 0
(-175 2425);
DISPLAY 0.978723 (-175 2425);
PAINT WHITE (-175 2425);
DISPLAY INVISIBLE (-175 2425);
FORCEPROP 2 LAST SEC 1
J 0
(-175 2475);
DISPLAY 0.680851 (-175 2475);
PAINT MONO (-175 2475);
DISPLAY INVISIBLE (-175 2475);
FORCEPROP 2 LAST SEC_TYPE 0402
J 0
(-175 2475);
DISPLAY 1.021277 (-175 2475);
PAINT ORANGE (-175 2475);
DISPLAY INVISIBLE (-175 2475);
FORCEPROP 2 LAST CDS_LOCATION R8D21
J 0
(-180 2375);
DISPLAY 0.617021 (-180 2375);
PAINT AQUA (-180 2375);
DISPLAY INVISIBLE (-180 2375);
FORCEPROP 2 LAST CDS_LIB mstr_discrete
R 3
J 0
(-225 2250);
PAINT MONO (-225 2250);
DISPLAY INVISIBLE (-225 2250);
FORCEADD RES..2
(-1525 2250);
FORCEPROP 1 LAST PACK_TYPE 0402
J 0
(-1485 2075);
DISPLAY 0.617021 (-1485 2075);
PAINT SKYBLUE (-1485 2075);
FORCEPROP 1 LAST VALUE 4.75K
J 0
(-1480 2325);
DISPLAY 0.617021 (-1480 2325);
PAINT SKYBLUE (-1480 2325);
FORCEPROP 1 LAST LOCATION R7D30
J 0
(-1480 2375);
DISPLAY 0.617021 (-1480 2375);
PAINT AQUA (-1480 2375);
FORCEPROP 1 LAST PART_NUMBER G21796-072
J 0
(-1485 2125);
DISPLAY 0.617021 (-1485 2125);
PAINT BLUE (-1485 2125);
FORCEPROP 1 LAST TOLERANCE 1%
J 0
(-1480 2275);
DISPLAY 0.617021 (-1480 2275);
PAINT SKYBLUE (-1480 2275);
FORCEPROP 1 LAST MATERIAL CHIP
J 0
(-1485 2175);
DISPLAY 0.617021 (-1485 2175);
PAINT SKYBLUE (-1485 2175);
FORCEPROP 1 LAST WATTAGE 1/16W
J 0
(-1485 2225);
DISPLAY 0.617021 (-1485 2225);
PAINT SKYBLUE (-1485 2225);
FORCEPROP 1 LASTPIN (-1525 2350) $PN 1
J 0
(-1520 2312);
DISPLAY 0.617021 (-1520 2312);
PAINT ORANGE (-1520 2312);
FORCEPROP 1 LASTPIN (-1525 2150) $PN 2
J 0
(-1520 2160);
DISPLAY 0.617021 (-1520 2160);
PAINT ORANGE (-1520 2160);
FORCEPROP 2 LAST ROOM UART_MUX
J 0
(-1475 2425);
DISPLAY 1.021277 (-1475 2425);
PAINT ORANGE (-1475 2425);
DISPLAY INVISIBLE (-1475 2425);
FORCEPROP 2 LAST SEC_TYPE 0402
J 0
(-1475 2475);
DISPLAY 1.021277 (-1475 2475);
PAINT ORANGE (-1475 2475);
DISPLAY INVISIBLE (-1475 2475);
FORCEPROP 2 LAST BOM_COST DEBUG
J 0
(-1475 2475);
DISPLAY 1.021277 (-1475 2475);
PAINT ORANGE (-1475 2475);
DISPLAY INVISIBLE (-1475 2475);
FORCEPROP 2 LAST SEC 1
J 0
(-1475 2475);
PAINT MONO (-1475 2475);
DISPLAY INVISIBLE (-1475 2475);
FORCEPROP 1 LAST PATH I121
J 0
(-1475 2425);
DISPLAY 0.978723 (-1475 2425);
PAINT WHITE (-1475 2425);
DISPLAY INVISIBLE (-1475 2425);
FORCEPROP 2 LAST CDS_LOCATION R7D30
J 0
(-1480 2375);
DISPLAY 0.617021 (-1480 2375);
PAINT AQUA (-1480 2375);
DISPLAY INVISIBLE (-1480 2375);
FORCEPROP 2 LAST CDS_LIB mstr_discrete
J 0
(-1525 2250);
PAINT ORANGE (-1525 2250);
DISPLAY INVISIBLE (-1525 2250);
FORCEADD P3V3_STBY..1
(-1525 2500);
FORCEPROP 3 LASTPIN (-1525 2450) SIG_NAME P3V3_STBY\g
J 0
(-1515 2460);
DISPLAY 0.659574 (-1515 2460);
PAINT MONO (-1515 2460);
DISPLAY INVISIBLE (-1515 2460);
FORCEPROP 1 LAST VOLTAGE 3.3V
J 0
(-1570 2457);
DISPLAY 0.340426 (-1570 2457);
PAINT SKYBLUE (-1570 2457);
DISPLAY INVISIBLE (-1570 2457);
FORCEPROP 1 LAST PATH I122
J 0
(-1480 2502);
DISPLAY 0.340426 (-1480 2502);
PAINT GREEN (-1480 2502);
DISPLAY INVISIBLE (-1480 2502);
FORCEPROP 1 LAST SIZE 1B
J 0
(-1480 2522);
DISPLAY 0.340426 (-1480 2522);
PAINT GREEN (-1480 2522);
DISPLAY INVISIBLE (-1480 2522);
FORCEPROP 2 LAST CDS_LIB mstr_symbols
J 0
(-1525 2500);
PAINT ORANGE (-1525 2500);
DISPLAY INVISIBLE (-1525 2500);
FORCEPROP 1 LAST BODY_TYPE PLUMBING
J 0
(-1570 2457);
DISPLAY 0.340426 (-1570 2457);
PAINT GREEN (-1570 2457);
DISPLAY INVISIBLE (-1570 2457);
FORCEPROP 1 LAST HDL_POWER P3V3_STBY
J 0
(-1825 2375);
DISPLAY 0.872340 (-1825 2375);
PAINT ORANGE (-1825 2375);
DISPLAY INVISIBLE (-1825 2375);
FORCEADD GND..1
(-300 1600);
FORCEPROP 3 LASTPIN (-300 1650) SIG_NAME GND\g
J 0
(-290 1660);
DISPLAY 0.659574 (-290 1660);
PAINT MONO (-290 1660);
DISPLAY INVISIBLE (-290 1660);
FORCEPROP 1 LAST VOLTAGE 0.0V
J 0
(-345 1557);
DISPLAY 0.340426 (-345 1557);
PAINT SKYBLUE (-345 1557);
DISPLAY INVISIBLE (-345 1557);
FORCEPROP 1 LAST SIZE 1B
J 0
(-225 1550);
DISPLAY 0.872340 (-225 1550);
PAINT AQUA (-225 1550);
DISPLAY INVISIBLE (-225 1550);
FORCEPROP 1 LAST PATH I123
J 0
(-225 1600);
DISPLAY 0.872340 (-225 1600);
PAINT AQUA (-225 1600);
DISPLAY INVISIBLE (-225 1600);
FORCEPROP 2 LAST CDS_LIB mstr_symbols
J 0
(-300 1600);
PAINT MONO (-300 1600);
DISPLAY INVISIBLE (-300 1600);
FORCEPROP 1 LAST BODY_TYPE PLUMBING
J 0
(-345 1557);
DISPLAY 0.340426 (-345 1557);
PAINT GREEN (-345 1557);
DISPLAY INVISIBLE (-345 1557);
FORCEPROP 1 LAST HDL_POWER GND
J 0
(-300 1750);
DISPLAY 0.872340 (-300 1750);
PAINT GREEN (-300 1750);
DISPLAY INVISIBLE (-300 1750);
FORCEADD CONN12_C73564003..1
(-775 1900);
FORCEPROP 1 LAST PART_NUMBER C73564-003
J 0
(-1075 1600);
DISPLAY 0.617021 (-1075 1600);
PAINT BLUE (-1075 1600);
FORCEPROP 2 LASTPIN (-425 2000) $PN 2
J 0
(-415 2010);
DISPLAY 0.617021 (-415 2010);
PAINT ORANGE (-415 2010);
FORCEPROP 2 LASTPIN (-425 1950) $PN 4
J 0
(-415 1960);
DISPLAY 0.617021 (-415 1960);
PAINT ORANGE (-415 1960);
FORCEPROP 1 LAST MATERIAL CONN
J 0
(-1075 2200);
DISPLAY 0.617021 (-1075 2200);
PAINT SKYBLUE (-1075 2200);
FORCEPROP 2 LASTPIN (-425 1900) $PN 6
J 0
(-415 1910);
DISPLAY 0.617021 (-415 1910);
PAINT ORANGE (-415 1910);
FORCEPROP 2 LASTPIN (-425 1750) $PN 12
J 0
(-415 1760);
DISPLAY 0.617021 (-415 1760);
PAINT ORANGE (-415 1760);
FORCEPROP 2 LASTPIN (-425 1800) $PN 10
J 0
(-415 1810);
DISPLAY 0.617021 (-415 1810);
PAINT ORANGE (-415 1810);
FORCEPROP 2 LASTPIN (-425 1850) $PN 8
J 0
(-415 1860);
DISPLAY 0.617021 (-415 1860);
PAINT ORANGE (-415 1860);
FORCEPROP 2 LASTPIN (-1125 1900) $PN 5
J 2
(-1135 1910);
DISPLAY 0.617021 (-1135 1910);
PAINT ORANGE (-1135 1910);
FORCEPROP 2 LASTPIN (-1125 1950) $PN 3
J 2
(-1135 1960);
DISPLAY 0.617021 (-1135 1960);
PAINT ORANGE (-1135 1960);
FORCEPROP 2 LASTPIN (-1125 1850) $PN 7
J 2
(-1135 1860);
DISPLAY 0.617021 (-1135 1860);
PAINT ORANGE (-1135 1860);
FORCEPROP 2 LASTPIN (-1125 1750) $PN 11
J 2
(-1135 1760);
DISPLAY 0.617021 (-1135 1760);
PAINT ORANGE (-1135 1760);
FORCEPROP 2 LASTPIN (-1125 1800) $PN 9
J 2
(-1135 1810);
DISPLAY 0.617021 (-1135 1810);
PAINT ORANGE (-1135 1810);
FORCEPROP 1 LAST LOCATION J8G2
J 0
(-1075 2250);
DISPLAY 0.617021 (-1075 2250);
PAINT AQUA (-1075 2250);
FORCEPROP 2 LASTPIN (-1125 2000) $PN 1
J 2
(-1135 2010);
DISPLAY 0.617021 (-1135 2010);
PAINT ORANGE (-1135 2010);
FORCEPROP 1 LAST PACK_TYPE PIP
J 0
(-1075 2300);
PAINT SKYBLUE (-1075 2300);
DISPLAY INVISIBLE (-1075 2300);
FORCEPROP 0 LAST ROOM SB
J 0
(-1075 2350);
DISPLAY 1.021277 (-1075 2350);
PAINT ORANGE (-1075 2350);
DISPLAY INVISIBLE (-1075 2350);
FORCEPROP 2 LAST SEC_TYPE PIP
J 0
(-1075 2300);
DISPLAY 1.021277 (-1075 2300);
PAINT ORANGE (-1075 2300);
DISPLAY INVISIBLE (-1075 2300);
FORCEPROP 2 LAST SEC 1
J 0
(-1075 2300);
DISPLAY 0.680851 (-1075 2300);
PAINT MONO (-1075 2300);
DISPLAY INVISIBLE (-1075 2300);
FORCEPROP 2 LAST CDS_LIB mstr_conn
J 0
(-775 1900);
PAINT ORANGE (-775 1900);
DISPLAY INVISIBLE (-775 1900);
FORCEPROP 1 LAST PATH I124
J 0
(-775 2200);
PAINT GREEN (-775 2200);
DISPLAY INVISIBLE (-775 2200);
FORCEPROP 0 LAST BOM_COST SB
J 0
(-1075 2450);
DISPLAY 1.021277 (-1075 2450);
PAINT ORANGE (-1075 2450);
DISPLAY INVISIBLE (-1075 2450);
FORCEADD GND..1
(-1250 1575);
FORCEPROP 3 LASTPIN (-1250 1625) SIG_NAME GND\g
J 0
(-1240 1635);
DISPLAY 0.659574 (-1240 1635);
PAINT MONO (-1240 1635);
DISPLAY INVISIBLE (-1240 1635);
FORCEPROP 1 LAST VOLTAGE 0.0V
J 0
(-1295 1532);
DISPLAY 0.340426 (-1295 1532);
PAINT SKYBLUE (-1295 1532);
DISPLAY INVISIBLE (-1295 1532);
FORCEPROP 2 LAST CDS_LIB mstr_symbols
J 0
(-1250 1575);
PAINT ORANGE (-1250 1575);
DISPLAY INVISIBLE (-1250 1575);
FORCEPROP 1 LAST PATH I125
J 0
(-1175 1575);
DISPLAY 0.872340 (-1175 1575);
PAINT AQUA (-1175 1575);
DISPLAY INVISIBLE (-1175 1575);
FORCEPROP 1 LAST SIZE 1B
J 0
(-1175 1525);
DISPLAY 0.872340 (-1175 1525);
PAINT AQUA (-1175 1525);
DISPLAY INVISIBLE (-1175 1525);
FORCEPROP 1 LAST BODY_TYPE PLUMBING
J 0
(-1295 1532);
DISPLAY 0.340426 (-1295 1532);
PAINT GREEN (-1295 1532);
DISPLAY INVISIBLE (-1295 1532);
FORCEPROP 1 LAST HDL_POWER GND
J 0
(-1250 1725);
DISPLAY 0.872340 (-1250 1725);
PAINT GREEN (-1250 1725);
DISPLAY INVISIBLE (-1250 1725);
FORCEADD OFFPAGE..5
(-2225 1950);
FORCEPROP 2 LAST $XR2 145 
J 0
(-2720 1950);
DISPLAY 0.638298 (-2720 1950);
PAINT MONO (-2720 1950);
FORCEPROP 2 LAST $XR1 157 
J 0
(-2600 1950);
DISPLAY 0.638298 (-2600 1950);
PAINT MONO (-2600 1950);
FORCEPROP 2 LAST $XR0 118 
J 0
(-2480 1950);
DISPLAY 0.638298 (-2480 1950);
PAINT MONO (-2480 1950);
FORCEPROP 2 LAST PATH I126
J 0
(-2500 2000);
DISPLAY 1.021277 (-2500 2000);
PAINT ORANGE (-2500 2000);
DISPLAY INVISIBLE (-2500 2000);
FORCEPROP 2 LAST CDS_LIB mstr_standard
J 0
(-2225 1950);
PAINT ORANGE (-2225 1950);
DISPLAY INVISIBLE (-2225 1950);
FORCEPROP 1 LAST OFFPAGE TRUE
J 0
(-1900 1825);
DISPLAY 0.872340 (-1900 1825);
PAINT GREEN (-1900 1825);
DISPLAY INVISIBLE (-1900 1825);
FORCEPROP 1 LAST COMMENT_BODY TRUE
J 0
(-2125 1875);
DISPLAY 0.872340 (-2125 1875);
PAINT GREEN (-2125 1875);
DISPLAY INVISIBLE (-2125 1875);
FORCEADD OFFPAGE..5
(-2225 1800);
FORCEPROP 2 LAST $XR0 190 
J 0
(-2480 1800);
DISPLAY 0.638298 (-2480 1800);
PAINT MONO (-2480 1800);
FORCEPROP 2 LAST PATH I127
J 0
(-2500 1850);
DISPLAY 1.021277 (-2500 1850);
PAINT ORANGE (-2500 1850);
DISPLAY INVISIBLE (-2500 1850);
FORCEPROP 2 LAST CDS_LIB mstr_standard
J 0
(-2225 1800);
PAINT ORANGE (-2225 1800);
DISPLAY INVISIBLE (-2225 1800);
FORCEPROP 1 LAST OFFPAGE TRUE
J 0
(-1900 1675);
DISPLAY 0.872340 (-1900 1675);
PAINT GREEN (-1900 1675);
DISPLAY INVISIBLE (-1900 1675);
FORCEPROP 1 LAST COMMENT_BODY TRUE
J 0
(-2125 1725);
DISPLAY 0.872340 (-2125 1725);
PAINT GREEN (-2125 1725);
DISPLAY INVISIBLE (-2125 1725);
FORCEADD P3V3_STBY..1
(-4275 5150);
FORCEPROP 3 LASTPIN (-4275 5100) SIG_NAME P3V3_STBY\g
J 0
(-4265 5110);
DISPLAY 0.659574 (-4265 5110);
PAINT MONO (-4265 5110);
DISPLAY INVISIBLE (-4265 5110);
FORCEPROP 1 LAST VOLTAGE 3.3V
J 0
(-4320 5107);
DISPLAY 0.340426 (-4320 5107);
PAINT SKYBLUE (-4320 5107);
DISPLAY INVISIBLE (-4320 5107);
FORCEPROP 1 LAST SIZE 1B
J 0
(-4230 5172);
DISPLAY 0.340426 (-4230 5172);
PAINT GREEN (-4230 5172);
DISPLAY INVISIBLE (-4230 5172);
FORCEPROP 2 LAST CDS_LIB mstr_symbols
J 0
(-4275 5150);
PAINT ORANGE (-4275 5150);
DISPLAY INVISIBLE (-4275 5150);
FORCEPROP 1 LAST PATH I128
J 0
(-4230 5152);
DISPLAY 0.340426 (-4230 5152);
PAINT GREEN (-4230 5152);
DISPLAY INVISIBLE (-4230 5152);
FORCEPROP 1 LAST BODY_TYPE PLUMBING
J 0
(-4320 5107);
DISPLAY 0.340426 (-4320 5107);
PAINT GREEN (-4320 5107);
DISPLAY INVISIBLE (-4320 5107);
FORCEPROP 1 LAST HDL_POWER P3V3_STBY
J 0
(-4575 5025);
DISPLAY 0.872340 (-4575 5025);
PAINT ORANGE (-4575 5025);
DISPLAY INVISIBLE (-4575 5025);
FORCEADD RES..1
R 1
(-4275 4900);
FORCEPROP 1 LAST VALUE 2.21K
J 0
(-4250 4925);
DISPLAY 0.617021 (-4250 4925);
PAINT SKYBLUE (-4250 4925);
FORCEPROP 1 LAST LOCATION R9A16
J 0
(-4250 5000);
DISPLAY 0.617021 (-4250 5000);
PAINT AQUA (-4250 5000);
FORCEPROP 1 LAST TOLERANCE 1%
J 0
(-4250 4875);
DISPLAY 0.617021 (-4250 4875);
PAINT SKYBLUE (-4250 4875);
FORCEPROP 1 LAST PACK_TYPE 0402
J 0
(-4250 4650);
DISPLAY 0.617021 (-4250 4650);
PAINT SKYBLUE (-4250 4650);
FORCEPROP 1 LAST MATERIAL CHIP
J 0
(-4250 4775);
DISPLAY 0.617021 (-4250 4775);
PAINT SKYBLUE (-4250 4775);
FORCEPROP 1 LASTPIN (-4275 5000) $PN 2
J 0
(-4312 4962);
DISPLAY 0.617021 (-4312 4962);
PAINT MONO (-4312 4962);
FORCEPROP 1 LASTPIN (-4275 4800) $PN 1
J 0
(-4312 4812);
DISPLAY 0.617021 (-4312 4812);
PAINT MONO (-4312 4812);
FORCEPROP 1 LAST PART_NUMBER G21796-112
J 0
(-4250 4725);
DISPLAY 0.617021 (-4250 4725);
PAINT BLUE (-4250 4725);
FORCEPROP 1 LAST WATTAGE 1/16W
J 0
(-4250 4825);
DISPLAY 0.617021 (-4250 4825);
PAINT SKYBLUE (-4250 4825);
FORCEPROP 2 LAST ROOM SB
J 0
(-4250 5050);
PAINT MONO (-4250 5050);
DISPLAY INVISIBLE (-4250 5050);
FORCEPROP 2 LAST CDS_SEC 1
J 0
(-4250 5050);
DISPLAY 1.404255 (-4250 5050);
PAINT ORANGE (-4250 5050);
DISPLAY INVISIBLE (-4250 5050);
FORCEPROP 2 LAST $SEC 1
J 0
(-4250 5050);
DISPLAY 0.936170 (-4250 5050);
PAINT MONO (-4250 5050);
DISPLAY INVISIBLE (-4250 5050);
FORCEPROP 2 LAST CDS_LOCATION R9A16
J 0
(-4250 5000);
DISPLAY 0.617021 (-4250 5000);
PAINT AQUA (-4250 5000);
DISPLAY INVISIBLE (-4250 5000);
FORCEPROP 2 LAST BOM_COST SB
J 0
(-4250 5050);
PAINT MONO (-4250 5050);
DISPLAY INVISIBLE (-4250 5050);
FORCEPROP 2 LAST CDS_LIB mstr_discrete
J 0
(-4275 4900);
PAINT MONO (-4275 4900);
DISPLAY INVISIBLE (-4275 4900);
FORCEPROP 1 LAST PATH I129
R 1
J 0
(-4425 4850);
DISPLAY 0.978723 (-4425 4850);
PAINT WHITE (-4425 4850);
DISPLAY INVISIBLE (-4425 4850);
FORCEADD GND..1
(-4850 4425);
FORCEPROP 3 LASTPIN (-4850 4475) SIG_NAME GND\g
J 0
(-4840 4485);
DISPLAY 0.659574 (-4840 4485);
PAINT MONO (-4840 4485);
DISPLAY INVISIBLE (-4840 4485);
FORCEPROP 2 LAST BOM_COST SB
J 0
(-4900 4500);
PAINT MONO (-4900 4500);
DISPLAY INVISIBLE (-4900 4500);
FORCEPROP 1 LAST SIZE 1B
J 0
(-4775 4375);
DISPLAY 1.404255 (-4775 4375);
PAINT GREEN (-4775 4375);
DISPLAY INVISIBLE (-4775 4375);
FORCEPROP 2 LAST CDS_LIB mstr_symbols
J 0
(-4850 4425);
PAINT MONO (-4850 4425);
DISPLAY INVISIBLE (-4850 4425);
FORCEPROP 1 LAST PATH I130
J 0
(-4775 4425);
DISPLAY 0.872340 (-4775 4425);
PAINT AQUA (-4775 4425);
DISPLAY INVISIBLE (-4775 4425);
FORCEPROP 2 LAST ROOM WBG_HEADERS_BIOS
J 0
(-5400 4500);
PAINT MONO (-5400 4500);
DISPLAY INVISIBLE (-5400 4500);
FORCEPROP 1 LAST VOLTAGE 0
J 0
(-4850 4425);
PAINT SKYBLUE (-4850 4425);
DISPLAY INVISIBLE (-4850 4425);
FORCEPROP 1 LAST BODY_TYPE PLUMBING
J 0
(-4895 4382);
DISPLAY 0.340426 (-4895 4382);
PAINT GREEN (-4895 4382);
DISPLAY INVISIBLE (-4895 4382);
FORCEPROP 1 LAST HDL_POWER GND
J 0
(-4850 4575);
DISPLAY 1.404255 (-4850 4575);
PAINT GREEN (-4850 4575);
DISPLAY INVISIBLE (-4850 4575);
FORCEADD CONN4_D42317002..1
R 2
(-5075 4600);
FORCEPROP 0 LAST POP NOPOP
J 0
(-5175 4350);
DISPLAY 1.021277 (-5175 4350);
PAINT RED (-5175 4350);
FORCEPROP 1 LAST LOCATION J9A1
J 2
(-4975 4850);
DISPLAY 0.617021 (-4975 4850);
PAINT AQUA (-4975 4850);
FORCEPROP 1 LAST PART_NUMBER D42317-002
J 2
(-4975 4400);
DISPLAY 0.617021 (-4975 4400);
PAINT BLUE (-4975 4400);
FORCEPROP 1 LAST MATERIAL CONN
J 2
(-4975 4800);
DISPLAY 0.617021 (-4975 4800);
PAINT SKYBLUE (-4975 4800);
FORCEPROP 2 LASTPIN (-4925 4650) $PN 1
J 0
(-4915 4660);
DISPLAY 0.617021 (-4915 4660);
PAINT MONO (-4915 4660);
FORCEPROP 2 LASTPIN (-4925 4600) $PN 2
J 0
(-4915 4610);
DISPLAY 0.617021 (-4915 4610);
PAINT MONO (-4915 4610);
FORCEPROP 2 LASTPIN (-4925 4500) $PN 4
J 0
(-4915 4510);
DISPLAY 0.617021 (-4915 4510);
PAINT MONO (-4915 4510);
FORCEPROP 2 LASTPIN (-4925 4550) $PN 3
J 0
(-4915 4560);
DISPLAY 0.617021 (-4915 4560);
PAINT MONO (-4915 4560);
FORCEPROP 1 LAST PACK_TYPE PIP
J 2
(-4975 4900);
PAINT SKYBLUE (-4975 4900);
DISPLAY INVISIBLE (-4975 4900);
FORCEPROP 2 LAST ROOM SB
J 0
(-4975 5000);
PAINT MONO (-4975 5000);
DISPLAY INVISIBLE (-4975 5000);
FORCEPROP 2 LAST CDS_LOCATION J9A1
J 2
(-4975 4850);
DISPLAY 0.617021 (-4975 4850);
PAINT AQUA (-4975 4850);
DISPLAY INVISIBLE (-4975 4850);
FORCEPROP 2 LAST $SEC 1
J 0
(-4975 4900);
PAINT MONO (-4975 4900);
DISPLAY INVISIBLE (-4975 4900);
FORCEPROP 2 LAST CDS_SEC 1
J 0
(-4975 4900);
PAINT MONO (-4975 4900);
DISPLAY INVISIBLE (-4975 4900);
FORCEPROP 0 LAST BOM_COST SB
J 0
(-4975 4950);
PAINT MONO (-4975 4950);
DISPLAY INVISIBLE (-4975 4950);
FORCEPROP 2 LAST CDS_LIB mstr_conn
J 0
(-5075 4600);
PAINT ORANGE (-5075 4600);
DISPLAY INVISIBLE (-5075 4600);
FORCEPROP 1 LAST PATH I131
J 2
(-5125 4800);
PAINT GREEN (-5125 4800);
DISPLAY INVISIBLE (-5125 4800);
FORCEADD DESIGN_NOTE..1
(675 2525);
FORCEPROP 0 LAST L1 TP JUMPER IS INSTALLED ON PINS 4 AND 6 FOR DISABLE IE
J 0
(475 2375);
DISPLAY 1.191489 (475 2375);
PAINT RED (475 2375);
FORCEPROP 2 LAST CDS_LIB mstr_symbols
J 0
(675 2525);
PAINT ORANGE (675 2525);
DISPLAY INVISIBLE (675 2525);
FORCEPROP 1 LAST COMMENT_BODY TRUE
J 0
(700 2625);
DISPLAY 0.978723 (700 2625);
PAINT ORANGE (700 2625);
DISPLAY INVISIBLE (700 2625);
FORCEADD DESIGN_NOTE..1
(-4800 1650);
FORCEPROP 0 LAST L1 UART CHANNEL LOCKED WHEN JUMPER IS INSTALLED ON PINS 7 AND 11
J 0
(-5000 1550);
DISPLAY 0.808511 (-5000 1550);
PAINT ORANGE (-5000 1550);
FORCEPROP 0 LAST L2 WHEN JUMPER IS INSTALLED ON PINS 7 AND 11, THE CURRENT
J 0
(-5000 1450);
DISPLAY 0.808511 (-5000 1450);
PAINT ORANGE (-5000 1450);
FORCEPROP 0 LAST L3 UART CHANNEL SELECTED ON THE OUTPUT OF UART MUX
J 0
(-5000 1400);
DISPLAY 0.808511 (-5000 1400);
PAINT ORANGE (-5000 1400);
FORCEPROP 0 LAST L4 WILL STAY SELECTED AFTER A POWER CYCLE
J 0
(-5000 1350);
DISPLAY 0.808511 (-5000 1350);
PAINT ORANGE (-5000 1350);
FORCEPROP 2 LAST CDS_LIB mstr_symbols
J 0
(-4800 1650);
PAINT ORANGE (-4800 1650);
DISPLAY INVISIBLE (-4800 1650);
FORCEPROP 1 LAST COMMENT_BODY TRUE
J 0
(-4775 1750);
DISPLAY 0.978723 (-4775 1750);
PAINT ORANGE (-4775 1750);
DISPLAY INVISIBLE (-4775 1750);
FORCEADD DNS..2
(-2145 4320);
PAINT RED (-2145 4320);
FORCEPROP 2 LAST CDS_LIB mstr_misc
J 0
(-2145 4320);
PAINT ORANGE (-2145 4320);
DISPLAY INVISIBLE (-2145 4320);
FORCEPROP 1 LAST COMMENT_BODY TRUE
R 1
J 0
(-2070 4095);
DISPLAY 0.872340 (-2070 4095);
PAINT GREEN (-2070 4095);
DISPLAY INVISIBLE (-2070 4095);
FORCEADD DESIGN_NOTE..1
(-725 5250);
FORCEPROP 0 LAST L1 QAT ENABLE
J 0
(-925 5125);
DISPLAY 1.021277 (-925 5125);
PAINT ORANGE (-925 5125);
FORCEPROP 2 LAST CDS_LIB mstr_symbols
J 0
(-725 5250);
PAINT ORANGE (-725 5250);
DISPLAY INVISIBLE (-725 5250);
FORCEPROP 1 LAST COMMENT_BODY TRUE
J 0
(-700 5350);
DISPLAY 1.361702 (-700 5350);
PAINT WHITE (-700 5350);
DISPLAY INVISIBLE (-700 5350);
FORCEADD CAD_NOTE..1
(-1100 1375);
FORCEPROP 0 LAST L1 PLACE TO THE LEFT OF J7G2
J 0
(-1250 1225);
DISPLAY 1.021277 (-1250 1225);
PAINT ORANGE (-1250 1225);
FORCEPROP 2 LAST CDS_LIB mstr_symbols
J 0
(-1100 1375);
PAINT ORANGE (-1100 1375);
DISPLAY INVISIBLE (-1100 1375);
FORCEPROP 1 LAST COMMENT_BODY TRUE
J 0
(-1075 1475);
DISPLAY 0.978723 (-1075 1475);
PAINT ORANGE (-1075 1475);
DISPLAY INVISIBLE (-1075 1475);
FORCEADD DESIGN_NOTE..1
(200 1450);
FORCEPROP 0 LAST L1 ADR DELAY IS DISABLED WHEN JUMPER IS INSTALLED ON PINS 10 AND 12
J 0
(0 1350);
DISPLAY 0.808511 (0 1350);
PAINT ORANGE (0 1350);
FORCEPROP 2 LAST CDS_LIB mstr_symbols
J 0
(200 1450);
PAINT ORANGE (200 1450);
DISPLAY INVISIBLE (200 1450);
FORCEPROP 1 LAST COMMENT_BODY TRUE
J 0
(225 1550);
DISPLAY 0.978723 (225 1550);
PAINT ORANGE (225 1550);
DISPLAY INVISIBLE (225 1550);
FORCEADD DESIGN_NOTE..1
(-4325 4125);
FORCEPROP 0 LAST L1 SATA RAID KEY
J 0
(-4525 4000);
DISPLAY 1.021277 (-4525 4000);
PAINT ORANGE (-4525 4000);
FORCEPROP 2 LAST CDS_LIB mstr_symbols
J 0
(-4325 4125);
PAINT MONO (-4325 4125);
DISPLAY INVISIBLE (-4325 4125);
FORCEPROP 1 LAST COMMENT_BODY TRUE
J 0
(-4300 4225);
DISPLAY 1.361702 (-4300 4225);
PAINT WHITE (-4300 4225);
DISPLAY INVISIBLE (-4300 4225);
FORCEADD INTEL_CORP_BPAGE..1
(2650 500);
FORCEPROP 1 LAST CDS_CON_LAST_MODIFIED Fri Jun 16 17:48:51 2017
J 0
(1225 825);
PAINT ORANGE (1225 825);
DISPLAY INVISIBLE (1225 825);
FORCEPROP 1 LAST CUSTOM_TXT_CDS <CURRENT_DESIGN_SHEET> OF <TOTAL_DESIGN_SHEETS>
J 0
(2150 525);
PAINT ORANGE (2150 525);
FORCEPROP 1 LAST CUSTOM_TXT_CDS <CON_LAST_MODIFIED>
J 0
(-1350 600);
PAINT ORANGE (-1350 600);
FORCEPROP 2 LAST CUSTOM_TXT_CDS <XR_PAGE_TITLE>
J 0
(-5240 5750);
DISPLAY 0.638298 (-5240 5750);
PAINT PINK (-5240 5750);
DISPLAY INVISIBLE (-5240 5750);
FORCEPROP 1 LAST SCH_TITLE LBG HEADERS (1/3)
J 0
(-5300 550);
DISPLAY 1.212766 (-5300 550);
PAINT ORANGE (-5300 550);
FORCEPROP 2 LAST CDS_LIB mstr_symbols
J 0
(2650 500);
PAINT MONO (2650 500);
DISPLAY INVISIBLE (2650 500);
FORCEPROP 2 LAST PAGE_BORDER TRUE
J 0
(-5240 5750);
DISPLAY 0.851064 (-5240 5750);
PAINT PINK (-5240 5750);
DISPLAY INVISIBLE (-5240 5750);
FORCEPROP 1 LAST COMMENT_BODY TRUE
J 0
(2662 512);
DISPLAY 0.468085 (2662 512);
PAINT GREEN (2662 512);
DISPLAY INVISIBLE (2662 512);
FORCEPROP 2 LAST CDS_XR_PAGE_TITLE CR-135 : @BASEBOARD_FAB2_LIB.BASEBOARD_FAB2(SCH_1):PAGE135
J 0
(-5240 5750);
DISPLAY 0.638298 (-5240 5750);
PAINT PINK (-5240 5750);
DISPLAY INVISIBLE (-5240 5750);
FORCEADD DESIGN_NOTE..1
(-4800 2500);
FORCEPROP 0 LAST L1 BMC DISABLED WHEN JUMPER IS INSTALLED ON PINS 3 AND 5
J 0
(-5000 2400);
DISPLAY 0.808511 (-5000 2400);
PAINT ORANGE (-5000 2400);
FORCEPROP 0 LAST L2 WHEN JUMPER IS INSTALLED ON PINS 3 AND 5, SRST# ON BMC
J 0
(-5000 2300);
DISPLAY 0.808511 (-5000 2300);
PAINT ORANGE (-5000 2300);
FORCEPROP 0 LAST L3 IS PULLED LOW AND ALL PINS ON BMC ARE
J 0
(-5000 2250);
DISPLAY 0.808511 (-5000 2250);
PAINT ORANGE (-5000 2250);
FORCEPROP 0 LAST L4 SET TO HIGH IMPEDANCE
J 0
(-5000 2200);
DISPLAY 0.808511 (-5000 2200);
PAINT ORANGE (-5000 2200);
FORCEPROP 2 LAST CDS_LIB mstr_symbols
J 0
(-4800 2500);
PAINT MONO (-4800 2500);
DISPLAY INVISIBLE (-4800 2500);
FORCEPROP 1 LAST COMMENT_BODY TRUE
J 0
(-4775 2600);
DISPLAY 0.978723 (-4775 2600);
PAINT ORANGE (-4775 2600);
DISPLAY INVISIBLE (-4775 2600);
WIRE 16 -1 (200 2475)(200 2325);
WIRE 16 -1 (-2150 4975)(-2150 4875);
WIRE 16 -1 (-2150 4225)(-2150 4175);
WIRE 16 -1 (-3875 5100)(-3875 5000);
WIRE 16 -1 (-225 2475)(-225 2350);
WIRE 16 -1 (-1525 2350)(-1525 2450);
WIRE 16 -1 (-300 1650)(-300 1750);
WIRE 16 -1 (-300 1750)(-300 1900);
WIRE 16 -1 (-300 1750)(-425 1750);
WIRE 16 -1 (-300 1900)(-425 1900);
WIRE 16 -1 (-1250 1625)(-1250 1750);
WIRE 16 -1 (-1250 1750)(-1250 1900);
WIRE 16 -1 (-1125 1750)(-1250 1750);
WIRE 16 -1 (-1125 1900)(-1250 1900);
WIRE 16 -1 (-4275 5100)(-4275 5000);
WIRE 16 -1 (-4850 4550)(-4850 4475);
WIRE 16 -1 (-4850 4650)(-4850 4550);
WIRE 16 -1 (-4925 4550)(-4850 4550);
WIRE 16 -1 (-4925 4650)(-4850 4650);
WIRE 16 -1 (-4925 4600)(-4275 4600);
FORCEPROP 2 LAST SIG_NAME PU_KEY_CONN_PIN2_R
J 0
(-4760 4610);
DISPLAY 0.617021 (-4760 4610);
PAINT ORANGE (-4760 4610);
FORCEPROP 2 LASTPROP $XRERR UNIQUE?
J 0
(-5000 4610);
DISPLAY 0.638298 (-5000 4610);
PAINT MONO (-5000 4610);
DISPLAY INVISIBLE (-5000 4610);
WIRE 16 -1 (-4275 4800)(-4275 4600);
WIRE 16 -1 (-2150 4425)(-2150 4525);
WIRE 16 -1 (-2150 4525)(-1550 4525);
WIRE 16 -1 (-2150 4675)(-2150 4525);
WIRE 16 -1 (-2625 3425)(-2625 2825);
WIRE 16 -1 (-2925 4500)(-3550 4500);
FORCEPROP 2 LAST SIG_NAME FM_PCH_SATA_RAID_KEY
J 0
(-3485 4510);
DISPLAY 0.617021 (-3485 4510);
PAINT ORANGE (-3485 4510);
WIRE 16 -1 (-425 1850)(625 1850);
FORCEPROP 2 LAST SIG_NAME TP_JUMPER_BLOCK_1_8
J 2
(600 1860);
DISPLAY 0.617021 (600 1860);
PAINT ORANGE (600 1860);
FORCEPROP 2 LASTPROP $XRERR UNIQUE?
J 0
(655 1850);
DISPLAY 0.638298 (655 1850);
PAINT MONO (655 1850);
DISPLAY INVISIBLE (655 1850);
WIRE 16 -1 (-775 5050)(-775 4825);
WIRE 16 -1 (-950 5075)(-950 4800);
WIRE 16 -1 (-25 5075)(-950 5075);
WIRE 16 -1 (-950 4800)(-25 4800);
WIRE 16 -1 (-25 4800)(-25 5075);
WIRE 16 -1 (625 2000)(-425 2000);
FORCEPROP 2 LAST SIG_NAME TP_JUMPER_BLOCK_1_2
J 2
(600 2010);
DISPLAY 0.617021 (600 2010);
PAINT ORANGE (600 2010);
FORCEPROP 2 LASTPROP $XRERR UNIQUE?
J 0
(655 2000);
DISPLAY 0.638298 (655 2000);
PAINT MONO (655 2000);
DISPLAY INVISIBLE (655 2000);
WIRE 16 -1 (200 1800)(625 1800);
FORCEPROP 2 LAST SIG_NAME FM_DIS_ADR_DLY
J 2
(600 1810);
DISPLAY 0.617021 (600 1810);
PAINT ORANGE (600 1810);
WIRE 16 -1 (200 2125)(200 1800);
WIRE 16 -1 (-425 1800)(200 1800);
WIRE 16 -1 (-425 1950)(-225 1950);
WIRE 16 -1 (-225 2150)(-225 1950);
WIRE 16 -1 (625 1950)(-225 1950);
FORCEPROP 0 LAST SIG_NAME FM_IE_DISABLE_N
J 2
(600 1960);
DISPLAY 0.617021 (600 1960);
PAINT ORANGE (600 1960);
WIRE 16 2175 (275 3900)(275 5350);
WIRE 16 2175 (-2350 3900)(275 3900);
WIRE 16 -1 (-3250 3075)(150 3075);
WIRE 16 -1 (-2175 2000)(-1125 2000);
FORCEPROP 2 LAST SIG_NAME TP_JUMPER_BLOCK_1_1
J 0
(-2110 2010);
DISPLAY 0.617021 (-2110 2010);
PAINT ORANGE (-2110 2010);
FORCEPROP 2 LASTPROP $XRERR UNIQUE?
J 0
(-2415 2000);
DISPLAY 0.638298 (-2415 2000);
PAINT MONO (-2415 2000);
DISPLAY INVISIBLE (-2415 2000);
WIRE 16 -1 (-2175 1950)(-1125 1950);
FORCEPROP 2 LAST SIG_NAME RST_BMC_SRST_N
J 0
(-2110 1960);
DISPLAY 0.617021 (-2110 1960);
PAINT ORANGE (-2110 1960);
WIRE 16 -1 (-2175 1850)(-1125 1850);
FORCEPROP 2 LAST SIG_NAME TP_JUMPER_BLOCK_ 1_7
J 0
(-2125 1860);
DISPLAY 0.617021 (-2125 1860);
PAINT ORANGE (-2125 1860);
FORCEPROP 2 LASTPROP $XRERR UNIQUE?
J 0
(-2415 1850);
DISPLAY 0.638298 (-2415 1850);
PAINT MONO (-2415 1850);
DISPLAY INVISIBLE (-2415 1850);
WIRE 16 -1 (-1525 1800)(-1125 1800);
WIRE 16 -1 (-1525 2150)(-1525 1800);
WIRE 16 -1 (-2175 1800)(-1525 1800);
FORCEPROP 2 LAST SIG_NAME FM_CPLD_UART_CH_LOCK_N
J 0
(-2125 1810);
DISPLAY 0.617021 (-2125 1810);
PAINT ORANGE (-2125 1810);
WIRE 16 -1 (-900 4975)(-175 4975);
WIRE 16 -1 (-3250 3325)(150 3325);
WIRE 16 -1 (-800 3425)(-800 2825);
WIRE 3 682 (300 3150)(250 3150);
WIRE 3 682 (250 3300)(300 3300);
WIRE 3 682 (300 3300)(300 3150);
WIRE 3 682 (300 3300)(350 3300);
WIRE 16 -1 (-3275 3450)(-3275 2775);
WIRE 16 -1 (175 3450)(-3275 3450);
WIRE 16 -1 (-3275 2775)(175 2775);
WIRE 16 -1 (175 2775)(175 3450);
WIRE 16 -1 (-1500 3400)(-1500 2800);
WIRE 16 2175 (-2450 3900)(-2450 5375);
WIRE 16 2175 (-5250 3900)(-2450 3900);
WIRE 16 -1 (-4925 4500)(-3875 4500);
FORCEPROP 2 LAST SIG_NAME FM_PCH_SATA_RAID_KEY_R
J 0
(-4760 4510);
DISPLAY 0.617021 (-4760 4510);
PAINT ORANGE (-4760 4510);
FORCEPROP 2 LASTPROP $XRERR UNIQUE?
J 0
(-5000 4510);
DISPLAY 0.638298 (-5000 4510);
PAINT MONO (-5000 4510);
DISPLAY INVISIBLE (-5000 4510);
WIRE 16 -1 (-3875 4500)(-3750 4500);
WIRE 16 -1 (-3875 4800)(-3875 4500);
DOT 1 (300 3300);
DOT 1 (-4850 4550);
DOT 1 (-1525 1800);
DOT 1 (-1250 1750);
DOT 1 (-300 1750);
DOT 1 (-225 1950);
DOT 1 (-2150 4525);
DOT 1 (200 1800);
DOT 1 (-3875 4500);
FORCENOTE
TP FAB4 UPDATE THE JUMPER NOTE 20170111
(400 3275) 0;
DISPLAY LEFT (400 3275);
DISPLAY 0.638298 (400 3275);
PAINT RED (400 3275);
FORCENOTE
NORMAL FUNCTIONALITY
(-775 2975) 0;
DISPLAY LEFT (-775 2975);
DISPLAY 1.021277 (-775 2975);
PAINT PURPLE (-775 2975);
FORCENOTE
NORMAL (DEFAULT)
(-775 3100) 0;
DISPLAY LEFT (-775 3100);
DISPLAY 1.361702 (-775 3100);
PAINT RED (-775 3100);
FORCENOTE
8-10
(-1250 2975) 0;
DISPLAY LEFT (-1250 2975);
DISPLAY 1.021277 (-1250 2975);
PAINT PURPLE (-1250 2975);
FORCENOTE
FOURCE POWER ON
(-775 3225) 0;
DISPLAY LEFT (-775 3225);
DISPLAY 1.021277 (-775 3225);
PAINT PURPLE (-775 3225);
FORCENOTE
ENABLE SATA <DEFAULT>
(-700 5000) 0;
DISPLAY LEFT (-700 5000);
DISPLAY 0.617021 (-700 5000);
PAINT PURPLE (-700 5000);
FORCENOTE
SYSTEM BEHAVIOR
(-2575 3350) 0;
DISPLAY LEFT (-2575 3350);
DISPLAY 1.021277 (-2575 3350);
PAINT PURPLE (-2575 3350);
FORCENOTE
ROOM=SB
(-5229 717) 0;
DISPLAY LEFT (-5229 717);
DISPLAY 0.957447 (-5229 717);
PAINT PURPLE (-5229 717);
FORCENOTE
JUMPER LOCATION
(-3200 3350) 0;
DISPLAY LEFT (-3200 3350);
DISPLAY 1.021277 (-3200 3350);
PAINT PURPLE (-3200 3350);
FORCENOTE
1-3
(-2775 3225) 0;
DISPLAY LEFT (-2775 3225);
DISPLAY 1.021277 (-2775 3225);
PAINT PURPLE (-2775 3225);
FORCENOTE
3-5
(-2775 3100) 0;
DISPLAY LEFT (-2775 3100);
DISPLAY 1.021277 (-2775 3100);
PAINT PURPLE (-2775 3100);
FORCENOTE
9-11
(-2775 2850) 0;
DISPLAY LEFT (-2775 2850);
DISPLAY 1.021277 (-2775 2850);
PAINT PURPLE (-2775 2850);
FORCENOTE
UART CHANNEL LOCKED
(-2575 2850) 0;
DISPLAY LEFT (-2575 2850);
DISPLAY 1.021277 (-2575 2850);
PAINT PURPLE (-2575 2850);
FORCENOTE
HIGH
(-900 5000) 0;
DISPLAY LEFT (-900 5000);
DISPLAY 0.617021 (-900 5000);
PAINT PURPLE (-900 5000);
FORCENOTE
DISABLE SATA
(-700 4900) 0;
DISPLAY LEFT (-700 4900);
DISPLAY 0.617021 (-700 4900);
PAINT PURPLE (-700 4900);
FORCENOTE
LOW
(-900 4900) 0;
DISPLAY LEFT (-900 4900);
DISPLAY 0.617021 (-900 4900);
PAINT PURPLE (-900 4900);
FORCENOTE
ENABLE PCIE_UP[7:0]
(-700 4850) 0;
DISPLAY LEFT (-700 4850);
DISPLAY 0.617021 (-700 4850);
PAINT PURPLE (-700 4850);
FORCENOTE
4-6
(-1250 3100) 0;
DISPLAY LEFT (-1250 3100);
DISPLAY 1.021277 (-1250 3100);
PAINT RED (-1250 3100);
FORCENOTE
BMC PINS SET TO HIGH IMPEDANCE
(-2575 3100) 0;
DISPLAY LEFT (-2575 3100);
DISPLAY 1.021277 (-2575 3100);
PAINT PURPLE (-2575 3100);
FORCENOTE
2-4
(-1250 3225) 0;
DISPLAY LEFT (-1250 3225);
DISPLAY 1.021277 (-1250 3225);
PAINT PURPLE (-1250 3225);
FORCENOTE
JUMPER LOCATION
(-1450 3350) 0;
DISPLAY LEFT (-1450 3350);
DISPLAY 1.021277 (-1450 3350);
PAINT PURPLE (-1450 3350);
FORCENOTE
SYSTEM BEHAVIOR
(-775 3350) 0;
DISPLAY LEFT (-775 3350);
DISPLAY 1.021277 (-775 3350);
PAINT PURPLE (-775 3350);
FORCENOTE
NORMAL FUNCTIONALITY
(-2575 3225) 0;
DISPLAY LEFT (-2575 3225);
DISPLAY 1.021277 (-2575 3225);
PAINT PURPLE (-2575 3225);
FORCENOTE
ADR DELAY DISABLED
(-775 2850) 0;
DISPLAY LEFT (-775 2850);
DISPLAY 1.021277 (-775 2850);
PAINT PURPLE (-775 2850);
FORCENOTE
10-12
(-1250 2850) 0;
DISPLAY LEFT (-1250 2850);
DISPLAY 1.021277 (-1250 2850);
PAINT PURPLE (-1250 2850);
FORCENOTE
NORMAL FUNCTIONALITY
(-2575 2975) 0;
DISPLAY LEFT (-2575 2975);
DISPLAY 1.021277 (-2575 2975);
PAINT PURPLE (-2575 2975);
FORCENOTE
7-9
(-2775 2975) 0;
DISPLAY LEFT (-2775 2975);
DISPLAY 1.021277 (-2775 2975);
PAINT PURPLE (-2775 2975);
FORCENOTE
TP FAB4 NOPOP J9A1 20170206
(-5175 4300) 0;
DISPLAY LEFT (-5175 4300);
DISPLAY 0.638298 (-5175 4300);
PAINT RED (-5175 4300);
QUIT
